# T6G (Grand Teton) — schematic netlist excerpt (pin names and nets, part order shuffled) for the footprints in the layout excerpt that follows; sources: Cadence DE-HDL packaged netlist, KiCad conversion of 04192023_DAF0TMB3IC0_F0TG_MB_C_brd_V02_OCP.brd

R1074  Q_RES  4.7K 5% CHIP  pkg 0201LF  page 298 : A = TEST0_RT_CPU0_P2 ; B = GND
C2413  Q_CAP  22UF 4V 20% X6S  pkg C0402  page 74 : A = PVDDCR_SOC_P1 ; B = GND
R1513  Q_RES  4.7K 5% EMPTY  pkg 0201LF  page 353 : A = P1V8_CPU1_RT_1D ; B = JTAG_TCK_RT_CPU1_P3
C243  Q_CAP  1UF 4V 20% X6S  pkg 0201  page 323 : A = P0V9_CPU1_RT0_2A ; B = GND

(kicad_pcb
	(version 20260206)
	(generator "pcbnew")
	(generator_version "10.0")
	(general
		(thickness 1.6)
		(legacy_teardrops no)
	)
	(paper "A4")
	(title_block
		(title "04192023_DAF0TMB3IC0_F0TG_MB_C_brd_V02_OCP.brd")
		(comment 1 "Grand Teton / footprints 5822-5825 of 8354")
	)
	(layers
		(0 "F.Cu" signal "TOP")
		(4 "In1.Cu" signal "GND")
		(6 "In2.Cu" signal "IN1")
		(8 "In3.Cu" signal "GND1")
		(10 "In4.Cu" signal "IN2")
		(12 "In5.Cu" signal "GND2")
		(14 "In6.Cu" signal "IN3")
		(16 "In7.Cu" signal "GND3")
		(18 "In8.Cu" signal "VCC")
		(20 "In9.Cu" signal "VCC1")
		(22 "In10.Cu" signal "GND4")
		(24 "In11.Cu" signal "IN4")
		(26 "In12.Cu" signal "GND5")
		(28 "In13.Cu" signal "IN5")
		(30 "In14.Cu" signal "GND6")
		(32 "In15.Cu" signal "IN6")
		(34 "In16.Cu" signal "GND7")
		(2 "B.Cu" signal "BOTTOM")
		(9 "F.Adhes" user "F.Adhesive")
		(11 "B.Adhes" user "B.Adhesive")
		(13 "F.Paste" user "Package Geometry/Pastemask Top")
		(15 "B.Paste" user "Package Geometry/Pastemask Bottom")
		(5 "F.SilkS" user "Ref Des/Silkscreen Top")
		(7 "B.SilkS" user "Ref Des/Silkscreen Bottom")
		(1 "F.Mask" user "Board Geometry/Soldermask Top")
		(3 "B.Mask" user "Board Geometry/Soldermask Bottom")
		(17 "Dwgs.User" user "User.Drawings")
		(19 "Cmts.User" user "User.Comments")
		(21 "Eco1.User" user "User.Eco1")
		(23 "Eco2.User" user "User.Eco2")
		(25 "Edge.Cuts" user "Board Geometry/Outline")
		(27 "Margin" user)
		(31 "F.CrtYd" user "Package Geometry/Place Bound Top")
		(29 "B.CrtYd" user "Package Geometry/Place Bound Bottom")
		(35 "F.Fab" user "Ref Des/Assembly Top")
		(33 "B.Fab" user "Ref Des/Assembly Bottom")
	)
	(footprint ""
		(layer "B.Cu")
		(at 398.893538 -393.96416 180)
		(property "Reference" "R1074"
			(at 0 0 0)
			(layer "B.SilkS")
			(hide yes)
			(effects
				(font
					(size 1.27 1.27)
				)
				(justify mirror)
			)
		)
		(property "Value" ""
			(at 0 0 0)
			(layer "B.Fab")
			(effects
				(font
					(size 1.27 1.27)
				)
				(justify mirror)
			)
		)
		(duplicate_pad_numbers_are_jumpers no)
		(fp_line
			(start 0.32512 0.175006)
			(end 0.32512 -0.175006)
			(stroke
				(width 0.1)
				(type default)
			)
			(layer "B.Fab")
		)
		(fp_line
			(start 0.32512 -0.175006)
			(end -0.32512 -0.175006)
			(stroke
				(width 0.1)
				(type default)
			)
			(layer "B.Fab")
		)
		(fp_line
			(start -0.32512 0.175006)
			(end 0.32512 0.175006)
			(stroke
				(width 0.1)
				(type default)
			)
			(layer "B.Fab")
		)
		(fp_line
			(start -0.32512 -0.175006)
			(end -0.32512 0.175006)
			(stroke
				(width 0.1)
				(type default)
			)
			(layer "B.Fab")
		)
		(pad "1" smd rect
			(at 0.2667 0)
			(size 0.3048 0.381)
			(layers "B.Cu" "B.Mask" "B.Paste")
			(net "TEST0_RT_CPU0_P2")
		)
		(pad "2" smd rect
			(at -0.2667 0 180)
			(size 0.3048 0.381)
			(layers "B.Cu" "B.Mask" "B.Paste")
			(net "GND")
		)
	)
	(footprint ""
		(layer "B.Cu")
		(at 115.610386 -251.781564)
		(property "Reference" "C2413"
			(at 0 0 0)
			(layer "B.SilkS")
			(hide yes)
			(effects
				(font
					(size 1.27 1.27)
				)
				(justify mirror)
			)
		)
		(property "Value" ""
			(at 0 0 0)
			(layer "B.Fab")
			(effects
				(font
					(size 1.27 1.27)
				)
				(justify mirror)
			)
		)
		(duplicate_pad_numbers_are_jumpers no)
		(fp_line
			(start -0.7874 -0.4064)
			(end -0.7874 0.4064)
			(stroke
				(width 0.1524)
				(type default)
			)
			(layer "B.SilkS")
		)
		(fp_line
			(start -0.7874 0.4064)
			(end 0.7874 0.4064)
			(stroke
				(width 0.1524)
				(type default)
			)
			(layer "B.SilkS")
		)
		(fp_line
			(start 0.7874 -0.4064)
			(end -0.7874 -0.4064)
			(stroke
				(width 0.1524)
				(type default)
			)
			(layer "B.SilkS")
		)
		(fp_line
			(start 0.7874 0.4064)
			(end 0.7874 -0.4064)
			(stroke
				(width 0.1524)
				(type default)
			)
			(layer "B.SilkS")
		)
		(fp_line
			(start -0.67945 -0.3048)
			(end -0.67945 0.3048)
			(stroke
				(width 0.1)
				(type default)
			)
			(layer "B.Fab")
		)
		(fp_line
			(start -0.67945 0.3048)
			(end -0.120396 0.3048)
			(stroke
				(width 0.1)
				(type default)
			)
			(layer "B.Fab")
		)
		(fp_line
			(start -0.12065 -0.3048)
			(end -0.67945 -0.3048)
			(stroke
				(width 0.1)
				(type default)
			)
			(layer "B.Fab")
		)
		(fp_line
			(start -0.12065 -0.2794)
			(end -0.12065 -0.3048)
			(stroke
				(width 0.1)
				(type default)
			)
			(layer "B.Fab")
		)
		(fp_line
			(start -0.120396 0.2794)
			(end 0.12065 0.2794)
			(stroke
				(width 0.1)
				(type default)
			)
			(layer "B.Fab")
		)
		(fp_line
			(start -0.120396 0.3048)
			(end -0.120396 0.2794)
			(stroke
				(width 0.1)
				(type default)
			)
			(layer "B.Fab")
		)
		(fp_line
			(start 0.12065 -0.305054)
			(end 0.12065 -0.2794)
			(stroke
				(width 0.1)
				(type default)
			)
			(layer "B.Fab")
		)
		(fp_line
			(start 0.12065 -0.2794)
			(end -0.12065 -0.2794)
			(stroke
				(width 0.1)
				(type default)
			)
			(layer "B.Fab")
		)
		(fp_line
			(start 0.12065 0.2794)
			(end 0.12065 0.3048)
			(stroke
				(width 0.1)
				(type default)
			)
			(layer "B.Fab")
		)
		(fp_line
			(start 0.12065 0.3048)
			(end 0.67945 0.3048)
			(stroke
				(width 0.1)
				(type default)
			)
			(layer "B.Fab")
		)
		(fp_line
			(start 0.67945 -0.305054)
			(end 0.12065 -0.305054)
			(stroke
				(width 0.1)
				(type default)
			)
			(layer "B.Fab")
		)
		(fp_line
			(start 0.67945 0.3048)
			(end 0.67945 -0.305054)
			(stroke
				(width 0.1)
				(type default)
			)
			(layer "B.Fab")
		)
		(pad "1" smd circle
			(at 0.40005 0 180)
			(size 0 0)
			(layers "B.Cu" "B.Mask" "B.Paste")
			(net "PVDDCR_SOC_P1")
		)
		(pad "2" smd circle
			(at -0.40005 0 180)
			(size 0 0)
			(layers "B.Cu" "B.Mask" "B.Paste")
			(net "GND")
		)
	)
	(footprint ""
		(layer "B.Cu")
		(at 164.338 -424.60037 -90)
		(property "Reference" "R1513"
			(at 0 0 90)
			(layer "B.SilkS")
			(hide yes)
			(effects
				(font
					(size 1.27 1.27)
				)
				(justify mirror)
			)
		)
		(property "Value" ""
			(at 0 0 90)
			(layer "B.Fab")
			(effects
				(font
					(size 1.27 1.27)
				)
				(justify mirror)
			)
		)
		(duplicate_pad_numbers_are_jumpers no)
		(fp_line
			(start -0.32512 0.175006)
			(end 0.32512 0.175006)
			(stroke
				(width 0.1)
				(type default)
			)
			(layer "B.Fab")
		)
		(fp_line
			(start 0.32512 0.175006)
			(end 0.32512 -0.175006)
			(stroke
				(width 0.1)
				(type default)
			)
			(layer "B.Fab")
		)
		(fp_line
			(start -0.32512 -0.175006)
			(end -0.32512 0.175006)
			(stroke
				(width 0.1)
				(type default)
			)
			(layer "B.Fab")
		)
		(fp_line
			(start 0.32512 -0.175006)
			(end -0.32512 -0.175006)
			(stroke
				(width 0.1)
				(type default)
			)
			(layer "B.Fab")
		)
		(pad "1" smd rect
			(at 0.2667 0 90)
			(size 0.3048 0.381)
			(layers "B.Cu" "B.Mask" "B.Paste")
			(net "P1V8_CPU1_RT_1D")
		)
		(pad "2" smd rect
			(at -0.2667 0 270)
			(size 0.3048 0.381)
			(layers "B.Cu" "B.Mask" "B.Paste")
			(net "JTAG_TCK_RT_CPU1_P3")
		)
	)
	(footprint ""
		(layer "B.Cu")
		(at 48.578516 -386.766562 90)
		(property "Reference" "C243"
			(at 0 0 90)
			(layer "B.SilkS")
			(hide yes)
			(effects
				(font
					(size 1.27 1.27)
				)
				(justify mirror)
			)
		)
		(property "Value" ""
			(at 0 0 90)
			(layer "B.Fab")
			(effects
				(font
					(size 1.27 1.27)
				)
				(justify mirror)
			)
		)
		(duplicate_pad_numbers_are_jumpers no)
		(fp_line
			(start 0.299974 -0.150114)
			(end -0.299974 -0.150114)
			(stroke
				(width 0.1)
				(type default)
			)
			(layer "B.Fab")
		)
		(fp_line
			(start -0.299974 -0.150114)
			(end -0.299974 0.150114)
			(stroke
				(width 0.1)
				(type default)
			)
			(layer "B.Fab")
		)
		(fp_line
			(start 0.299974 0.150114)
			(end 0.299974 -0.150114)
			(stroke
				(width 0.1)
				(type default)
			)
			(layer "B.Fab")
		)
		(fp_line
			(start -0.299974 0.150114)
			(end 0.299974 0.150114)
			(stroke
				(width 0.1)
				(type default)
			)
			(layer "B.Fab")
		)
		(pad "1" smd rect
			(at 0.2667 0 270)
			(size 0.3048 0.381)
			(layers "B.Cu" "B.Mask" "B.Paste")
			(net "P0V9_CPU1_RT0_2A")
		)
		(pad "2" smd rect
			(at -0.2667 0 270)
			(size 0.3048 0.381)
			(layers "B.Cu" "B.Mask" "B.Paste")
			(net "GND")
		)
	)
)
